(kicad_pcb
	(version 20260206)
	(generator "pcbnew")
	(generator_version "10.0")
	(general
		(thickness 1.6)
		(legacy_teardrops no)
	)
	(paper "A4")
	(title_block
		(title "peb — Lightning_PEB_BRD.brd")
		(comment 1 "Lightning (Wiwynn / Facebook NVMe JBOF) / footprints 107-113 of 2563")
	)
	(layers
		(0 "F.Cu" signal "TOP")
		(4 "In1.Cu" signal "L2GND")
		(6 "In2.Cu" signal "L3")
		(8 "In3.Cu" signal "L4VCC")
		(10 "In4.Cu" signal "L5VCC")
		(12 "In5.Cu" signal "L6")
		(14 "In6.Cu" signal "L7GND")
		(2 "B.Cu" signal "BOTTOM")
		(9 "F.Adhes" user "F.Adhesive")
		(11 "B.Adhes" user "B.Adhesive")
		(13 "F.Paste" user "Package Geometry/Pastemask Top")
		(15 "B.Paste" user "Package Geometry/Pastemask Bottom")
		(5 "F.SilkS" user "Ref Des/Silkscreen Top")
		(7 "B.SilkS" user "Ref Des/Silkscreen Bottom")
		(1 "F.Mask" user "Board Geometry/Soldermask Top")
		(3 "B.Mask" user "Board Geometry/Soldermask Bottom")
		(17 "Dwgs.User" user "User.Drawings")
		(19 "Cmts.User" user "User.Comments")
		(21 "Eco1.User" user "User.Eco1")
		(23 "Eco2.User" user "User.Eco2")
		(25 "Edge.Cuts" user "Board Geometry/Outline")
		(27 "Margin" user)
		(31 "F.CrtYd" user "Package Geometry/Place Bound Top")
		(29 "B.CrtYd" user "Package Geometry/Place Bound Bottom")
		(35 "F.Fab" user "Ref Des/Assembly Top")
		(33 "B.Fab" user "Ref Des/Assembly Bottom")
	)
	(footprint ""
		(layer "F.Cu")
		(at 212.594444 -40.19296 -90)
		(property "Reference" "C641"
			(at 0 0 270)
			(layer "F.SilkS")
			(hide yes)
			(effects
				(font
					(size 1.27 1.27)
				)
			)
		)
		(property "Value" "SCD22U10V2KX-1GP"
			(at 1.1811 -2.7051 270)
			(unlocked yes)
			(layer "F.Fab")
			(hide yes)
			(effects
				(font
					(size 1.016 1.016)
					(thickness 0.1524)
				)
			)
		)
		(property "Device Type" "C402H22"
			(at 1.1811 -4.2291 270)
			(unlocked yes)
			(layer "F.Fab")
			(hide yes)
			(effects
				(font
					(size 1.016 1.016)
					(thickness 0.1524)
				)
			)
		)
		(duplicate_pad_numbers_are_jumpers no)
		(fp_rect
			(start -0.4318 0.9525)
			(end 0.4318 -0.9525)
			(stroke
				(width 0)
				(type default)
			)
			(fill no)
			(layer "F.CrtYd")
		)
		(fp_rect
			(start -0.4318 0.9525)
			(end 0.4318 -0.9525)
			(stroke
				(width 0)
				(type default)
			)
			(fill no)
			(layer "F.Fab")
		)
		(pad "1" smd custom
			(at 0 -0.4445 270)
			(size 0.1524 0.1524)
			(layers "F.Cu" "F.Mask" "F.Paste")
			(net "PCIE_TX_CAP_P78")
			(options
				(clearance outline)
				(anchor circle)
			)
			(primitives
				(gr_poly
					(pts
						(arc
							(start 0.3048 -0.2032)
							(mid 0.275042 -0.275042)
							(end 0.2032 -0.3048)
						)
						(arc
							(start -0.2032 -0.3048)
							(mid -0.275042 -0.275042)
							(end -0.3048 -0.2032)
						)
						(arc
							(start -0.3048 0.2032)
							(mid -0.275042 0.275042)
							(end -0.2032 0.3048)
						)
						(arc
							(start 0.2032 0.3048)
							(mid 0.275042 0.275042)
							(end 0.3048 0.2032)
						)
					)
					(width 0)
					(fill yes)
				)
			)
		)
		(pad "2" smd custom
			(at 0 0.4445 270)
			(size 0.1524 0.1524)
			(layers "F.Cu" "F.Mask" "F.Paste")
			(net "PCIE_TX_P78")
			(options
				(clearance outline)
				(anchor circle)
			)
			(primitives
				(gr_poly
					(pts
						(arc
							(start 0.3048 -0.2032)
							(mid 0.275042 -0.275042)
							(end 0.2032 -0.3048)
						)
						(arc
							(start -0.2032 -0.3048)
							(mid -0.275042 -0.275042)
							(end -0.3048 -0.2032)
						)
						(arc
							(start -0.3048 0.2032)
							(mid -0.275042 0.275042)
							(end -0.2032 0.3048)
						)
						(arc
							(start 0.2032 0.3048)
							(mid 0.275042 0.275042)
							(end 0.3048 0.2032)
						)
					)
					(width 0)
					(fill yes)
				)
			)
		)
	)
	(footprint ""
		(layer "F.Cu")
		(at 135.358124 -208.889092 180)
		(property "Reference" "R7926"
			(at 0 0 180)
			(layer "F.SilkS")
			(hide yes)
			(effects
				(font
					(size 1.27 1.27)
				)
			)
		)
		(property "Value" "0R2J-2-GP"
			(at 0.064008 -3.993896 180)
			(unlocked yes)
			(layer "F.Fab")
			(hide yes)
			(effects
				(font
					(size 1.016 1.016)
					(thickness 0.1524)
				)
			)
		)
		(property "Device Type" "R402H16"
			(at 0.064008 -5.517896 180)
			(unlocked yes)
			(layer "F.Fab")
			(hide yes)
			(effects
				(font
					(size 1.016 1.016)
					(thickness 0.1524)
				)
			)
		)
		(duplicate_pad_numbers_are_jumpers no)
		(fp_line
			(start 0.508 -0.9398)
			(end -0.508 -0.9398)
			(stroke
				(width 0.1524)
				(type default)
			)
			(layer "F.SilkS")
		)
		(fp_line
			(start -0.508 -0.9398)
			(end -0.508 0.9398)
			(stroke
				(width 0.1524)
				(type default)
			)
			(layer "F.SilkS")
		)
		(fp_rect
			(start -0.508 0.9398)
			(end 0.508 -0.9398)
			(stroke
				(width 0)
				(type default)
			)
			(fill no)
			(layer "F.CrtYd")
		)
		(fp_rect
			(start -0.508 0.9398)
			(end 0.508 -0.9398)
			(stroke
				(width 0)
				(type default)
			)
			(fill no)
			(layer "F.Fab")
		)
		(pad "1" smd custom
			(at 0 -0.4445 180)
			(size 0.1397 0.1397)
			(layers "F.Cu" "F.Mask" "F.Paste")
			(net "SSD_PRSNT#6")
			(options
				(clearance outline)
				(anchor circle)
			)
			(primitives
				(gr_poly
					(pts
						(arc
							(start -0.1778 -0.2794)
							(mid -0.249642 -0.249642)
							(end -0.2794 -0.1778)
						)
						(arc
							(start -0.2794 0.1778)
							(mid -0.249642 0.249642)
							(end -0.1778 0.2794)
						)
						(arc
							(start 0.1778 0.2794)
							(mid 0.249642 0.249642)
							(end 0.2794 0.1778)
						)
						(arc
							(start 0.2794 -0.1778)
							(mid 0.249642 -0.249642)
							(end 0.1778 -0.2794)
						)
					)
					(width 0)
					(fill yes)
				)
			)
		)
		(pad "2" smd custom
			(at 0 0.4445 180)
			(size 0.1397 0.1397)
			(layers "F.Cu" "F.Mask" "F.Paste")
			(net "SSD_PRSNT#6_R")
			(options
				(clearance outline)
				(anchor circle)
			)
			(primitives
				(gr_poly
					(pts
						(arc
							(start -0.1778 -0.2794)
							(mid -0.249642 -0.249642)
							(end -0.2794 -0.1778)
						)
						(arc
							(start -0.2794 0.1778)
							(mid -0.249642 0.249642)
							(end -0.1778 0.2794)
						)
						(arc
							(start 0.1778 0.2794)
							(mid 0.249642 0.249642)
							(end 0.2794 0.1778)
						)
						(arc
							(start 0.2794 -0.1778)
							(mid 0.249642 -0.249642)
							(end 0.1778 -0.2794)
						)
					)
					(width 0)
					(fill yes)
				)
			)
		)
	)
	(footprint ""
		(layer "F.Cu")
		(at 142.23238 -34.774886 -90)
		(property "Reference" "R214"
			(at 0 0 270)
			(layer "F.SilkS")
			(hide yes)
			(effects
				(font
					(size 1.27 1.27)
				)
			)
		)
		(property "Value" "4K7R2F-GP"
			(at 0.064008 -3.993896 270)
			(unlocked yes)
			(layer "F.Fab")
			(hide yes)
			(effects
				(font
					(size 1.016 1.016)
					(thickness 0.1524)
				)
			)
		)
		(property "Device Type" "R402H16"
			(at 0.064008 -5.517896 270)
			(unlocked yes)
			(layer "F.Fab")
			(hide yes)
			(effects
				(font
					(size 1.016 1.016)
					(thickness 0.1524)
				)
			)
		)
		(duplicate_pad_numbers_are_jumpers no)
		(fp_line
			(start -0.508 -0.9398)
			(end -0.508 0.9398)
			(stroke
				(width 0.1524)
				(type default)
			)
			(layer "F.SilkS")
		)
		(fp_line
			(start 0.508 -0.9398)
			(end -0.508 -0.9398)
			(stroke
				(width 0.1524)
				(type default)
			)
			(layer "F.SilkS")
		)
		(fp_rect
			(start -0.508 0.9398)
			(end 0.508 -0.9398)
			(stroke
				(width 0)
				(type default)
			)
			(fill no)
			(layer "F.CrtYd")
		)
		(fp_rect
			(start -0.508 0.9398)
			(end 0.508 -0.9398)
			(stroke
				(width 0)
				(type default)
			)
			(fill no)
			(layer "F.Fab")
		)
		(pad "1" smd custom
			(at 0 -0.4445 270)
			(size 0.1397 0.1397)
			(layers "F.Cu" "F.Mask" "F.Paste")
			(net "P3V3_STBY")
			(options
				(clearance outline)
				(anchor circle)
			)
			(primitives
				(gr_poly
					(pts
						(arc
							(start -0.1778 -0.2794)
							(mid -0.249642 -0.249642)
							(end -0.2794 -0.1778)
						)
						(arc
							(start -0.2794 0.1778)
							(mid -0.249642 0.249642)
							(end -0.1778 0.2794)
						)
						(arc
							(start 0.1778 0.2794)
							(mid 0.249642 0.249642)
							(end 0.2794 0.1778)
						)
						(arc
							(start 0.2794 -0.1778)
							(mid 0.249642 -0.249642)
							(end 0.1778 -0.2794)
						)
					)
					(width 0)
					(fill yes)
				)
			)
		)
		(pad "2" smd custom
			(at 0 0.4445 270)
			(size 0.1397 0.1397)
			(layers "F.Cu" "F.Mask" "F.Paste")
			(net "CLK_P_2_R")
			(options
				(clearance outline)
				(anchor circle)
			)
			(primitives
				(gr_poly
					(pts
						(arc
							(start -0.1778 -0.2794)
							(mid -0.249642 -0.249642)
							(end -0.2794 -0.1778)
						)
						(arc
							(start -0.2794 0.1778)
							(mid -0.249642 0.249642)
							(end -0.1778 0.2794)
						)
						(arc
							(start 0.1778 0.2794)
							(mid 0.249642 0.249642)
							(end 0.2794 0.1778)
						)
						(arc
							(start 0.2794 -0.1778)
							(mid 0.249642 -0.249642)
							(end 0.1778 -0.2794)
						)
					)
					(width 0)
					(fill yes)
				)
			)
		)
	)
	(footprint ""
		(layer "F.Cu")
		(at 117.5258 -95.0722)
		(property "Reference" "C693"
			(at 0 0 0)
			(layer "F.SilkS")
			(hide yes)
			(effects
				(font
					(size 1.27 1.27)
				)
			)
		)
		(property "Value" "SCD01U50V2KX-1GP"
			(at 1.1811 -2.7051 0)
			(unlocked yes)
			(layer "F.Fab")
			(hide yes)
			(effects
				(font
					(size 1.016 1.016)
					(thickness 0.1524)
				)
			)
		)
		(property "Device Type" "C402H22"
			(at 1.1811 -4.2291 0)
			(unlocked yes)
			(layer "F.Fab")
			(hide yes)
			(effects
				(font
					(size 1.016 1.016)
					(thickness 0.1524)
				)
			)
		)
		(duplicate_pad_numbers_are_jumpers no)
		(fp_rect
			(start -0.4318 0.9525)
			(end 0.4318 -0.9525)
			(stroke
				(width 0)
				(type default)
			)
			(fill no)
			(layer "F.CrtYd")
		)
		(fp_rect
			(start -0.4318 0.9525)
			(end 0.4318 -0.9525)
			(stroke
				(width 0)
				(type default)
			)
			(fill no)
			(layer "F.Fab")
		)
		(pad "1" smd custom
			(at 0 -0.4445)
			(size 0.1524 0.1524)
			(layers "F.Cu" "F.Mask" "F.Paste")
			(net "P3V3_STBY")
			(options
				(clearance outline)
				(anchor circle)
			)
			(primitives
				(gr_poly
					(pts
						(arc
							(start 0.3048 -0.2032)
							(mid 0.275042 -0.275042)
							(end 0.2032 -0.3048)
						)
						(arc
							(start -0.2032 -0.3048)
							(mid -0.275042 -0.275042)
							(end -0.3048 -0.2032)
						)
						(arc
							(start -0.3048 0.2032)
							(mid -0.275042 0.275042)
							(end -0.2032 0.3048)
						)
						(arc
							(start 0.2032 0.3048)
							(mid 0.275042 0.275042)
							(end 0.3048 0.2032)
						)
					)
					(width 0)
					(fill yes)
				)
			)
		)
		(pad "2" smd custom
			(at 0 0.4445)
			(size 0.1524 0.1524)
			(layers "F.Cu" "F.Mask" "F.Paste")
			(net "GND")
			(options
				(clearance outline)
				(anchor circle)
			)
			(primitives
				(gr_poly
					(pts
						(arc
							(start 0.3048 -0.2032)
							(mid 0.275042 -0.275042)
							(end 0.2032 -0.3048)
						)
						(arc
							(start -0.2032 -0.3048)
							(mid -0.275042 -0.275042)
							(end -0.3048 -0.2032)
						)
						(arc
							(start -0.3048 0.2032)
							(mid -0.275042 0.275042)
							(end -0.2032 0.3048)
						)
						(arc
							(start 0.2032 0.3048)
							(mid 0.275042 0.275042)
							(end 0.3048 0.2032)
						)
					)
					(width 0)
					(fill yes)
				)
			)
		)
	)
	(footprint ""
		(layer "F.Cu")
		(at 316.392052 -212.420454 180)
		(property "Reference" "C68"
			(at 0 0 180)
			(layer "F.SilkS")
			(hide yes)
			(effects
				(font
					(size 1.27 1.27)
				)
			)
		)
		(property "Value" "SCD22U10V2KX-1GP"
			(at 1.1811 -2.7051 180)
			(unlocked yes)
			(layer "F.Fab")
			(hide yes)
			(effects
				(font
					(size 1.016 1.016)
					(thickness 0.1524)
				)
			)
		)
		(property "Device Type" "C402H22"
			(at 1.1811 -4.2291 180)
			(unlocked yes)
			(layer "F.Fab")
			(hide yes)
			(effects
				(font
					(size 1.016 1.016)
					(thickness 0.1524)
				)
			)
		)
		(duplicate_pad_numbers_are_jumpers no)
		(fp_rect
			(start -0.4318 0.9525)
			(end 0.4318 -0.9525)
			(stroke
				(width 0)
				(type default)
			)
			(fill no)
			(layer "F.CrtYd")
		)
		(fp_rect
			(start -0.4318 0.9525)
			(end 0.4318 -0.9525)
			(stroke
				(width 0)
				(type default)
			)
			(fill no)
			(layer "F.Fab")
		)
		(pad "1" smd custom
			(at 0 -0.4445 180)
			(size 0.1524 0.1524)
			(layers "F.Cu" "F.Mask" "F.Paste")
			(net "PCIE_TX_CAP_P23")
			(options
				(clearance outline)
				(anchor circle)
			)
			(primitives
				(gr_poly
					(pts
						(arc
							(start 0.3048 -0.2032)
							(mid 0.275042 -0.275042)
							(end 0.2032 -0.3048)
						)
						(arc
							(start -0.2032 -0.3048)
							(mid -0.275042 -0.275042)
							(end -0.3048 -0.2032)
						)
						(arc
							(start -0.3048 0.2032)
							(mid -0.275042 0.275042)
							(end -0.2032 0.3048)
						)
						(arc
							(start 0.2032 0.3048)
							(mid 0.275042 0.275042)
							(end 0.3048 0.2032)
						)
					)
					(width 0)
					(fill yes)
				)
			)
		)
		(pad "2" smd custom
			(at 0 0.4445 180)
			(size 0.1524 0.1524)
			(layers "F.Cu" "F.Mask" "F.Paste")
			(net "PCIE_TX_P23")
			(options
				(clearance outline)
				(anchor circle)
			)
			(primitives
				(gr_poly
					(pts
						(arc
							(start 0.3048 -0.2032)
							(mid 0.275042 -0.275042)
							(end 0.2032 -0.3048)
						)
						(arc
							(start -0.2032 -0.3048)
							(mid -0.275042 -0.275042)
							(end -0.3048 -0.2032)
						)
						(arc
							(start -0.3048 0.2032)
							(mid -0.275042 0.275042)
							(end -0.2032 0.3048)
						)
						(arc
							(start 0.2032 0.3048)
							(mid 0.275042 0.275042)
							(end 0.3048 0.2032)
						)
					)
					(width 0)
					(fill yes)
				)
			)
		)
	)
	(footprint ""
		(layer "F.Cu")
		(at 15.9766 -81.8642 -90)
		(property "Reference" "TP163"
			(at 0 0 270)
			(layer "F.SilkS")
			(hide yes)
			(effects
				(font
					(size 1.27 1.27)
				)
			)
		)
		(property "Value" "TPAD28-2-GP"
			(at -0.0127 -1.6637 270)
			(unlocked yes)
			(layer "F.Fab")
			(hide yes)
			(effects
				(font
					(size 1.016 1.016)
					(thickness 0.1524)
				)
			)
		)
		(property "Device Type" "TPAD28"
			(at -0.0127 -3.1877 270)
			(unlocked yes)
			(layer "F.Fab")
			(hide yes)
			(effects
				(font
					(size 1.016 1.016)
					(thickness 0.1524)
				)
			)
		)
		(duplicate_pad_numbers_are_jumpers no)
		(fp_poly
			(pts
				(arc
					(start 0 -0.3556)
					(mid 0 0.3556)
					(end 0 -0.3556)
				)
			)
			(stroke
				(width 0)
				(type default)
			)
			(fill no)
			(layer "F.CrtYd")
		)
		(fp_poly
			(pts
				(arc
					(start 0 -0.6096)
					(mid 0 0.6096)
					(end 0 -0.6096)
				)
			)
			(stroke
				(width 0)
				(type default)
			)
			(fill no)
			(layer "F.Fab")
		)
		(pad "1" smd circle
			(at 0 0 270)
			(size 0.7112 0.7112)
			(layers "F.Cu" "F.Mask" "F.Paste")
			(net "NIC_JTDI")
		)
	)
	(footprint ""
		(layer "F.Cu")
		(at 77.827124 -183.235092)
		(property "Reference" "R7958"
			(at 0 0 0)
			(layer "F.SilkS")
			(hide yes)
			(effects
				(font
					(size 1.27 1.27)
				)
			)
		)
		(property "Value" "0R2J-2-GP"
			(at 0.064008 -3.993896 0)
			(unlocked yes)
			(layer "F.Fab")
			(hide yes)
			(effects
				(font
					(size 1.016 1.016)
					(thickness 0.1524)
				)
			)
		)
		(property "Device Type" "R402H16"
			(at 0.064008 -5.517896 0)
			(unlocked yes)
			(layer "F.Fab")
			(hide yes)
			(effects
				(font
					(size 1.016 1.016)
					(thickness 0.1524)
				)
			)
		)
		(duplicate_pad_numbers_are_jumpers no)
		(fp_line
			(start -0.508 -0.9398)
			(end -0.508 0.9398)
			(stroke
				(width 0.1524)
				(type default)
			)
			(layer "F.SilkS")
		)
		(fp_line
			(start 0.508 -0.9398)
			(end -0.508 -0.9398)
			(stroke
				(width 0.1524)
				(type default)
			)
			(layer "F.SilkS")
		)
		(fp_rect
			(start -0.508 0.9398)
			(end 0.508 -0.9398)
			(stroke
				(width 0)
				(type default)
			)
			(fill no)
			(layer "F.CrtYd")
		)
		(fp_rect
			(start -0.508 0.9398)
			(end 0.508 -0.9398)
			(stroke
				(width 0)
				(type default)
			)
			(fill no)
			(layer "F.Fab")
		)
		(pad "1" smd custom
			(at 0 -0.4445)
			(size 0.1397 0.1397)
			(layers "F.Cu" "F.Mask" "F.Paste")
			(net "SSD_PWREN5")
			(options
				(clearance outline)
				(anchor circle)
			)
			(primitives
				(gr_poly
					(pts
						(arc
							(start -0.1778 -0.2794)
							(mid -0.249642 -0.249642)
							(end -0.2794 -0.1778)
						)
						(arc
							(start -0.2794 0.1778)
							(mid -0.249642 0.249642)
							(end -0.1778 0.2794)
						)
						(arc
							(start 0.1778 0.2794)
							(mid 0.249642 0.249642)
							(end 0.2794 0.1778)
						)
						(arc
							(start 0.2794 -0.1778)
							(mid 0.249642 -0.249642)
							(end 0.1778 -0.2794)
						)
					)
					(width 0)
					(fill yes)
				)
			)
		)
		(pad "2" smd custom
			(at 0 0.4445)
			(size 0.1397 0.1397)
			(layers "F.Cu" "F.Mask" "F.Paste")
			(net "SSD_PWREN5_R")
			(options
				(clearance outline)
				(anchor circle)
			)
			(primitives
				(gr_poly
					(pts
						(arc
							(start -0.1778 -0.2794)
							(mid -0.249642 -0.249642)
							(end -0.2794 -0.1778)
						)
						(arc
							(start -0.2794 0.1778)
							(mid -0.249642 0.249642)
							(end -0.1778 0.2794)
						)
						(arc
							(start 0.1778 0.2794)
							(mid 0.249642 0.249642)
							(end 0.2794 0.1778)
						)
						(arc
							(start 0.2794 -0.1778)
							(mid 0.249642 -0.249642)
							(end 0.1778 -0.2794)
						)
					)
					(width 0)
					(fill yes)
				)
			)
		)
	)
)
